# S9S_MB_2U (Grand Teton) — schematic netlist excerpt (pin names and nets, part order shuffled) for the footprints in the layout excerpt that follows; sources: Cadence DE-HDL packaged netlist, KiCad conversion of 03242023_DA0F0TMBIJ0_F0T_Motherboard_J_brd_V01_OCP.brd

R4782  Q_RES  33.2 1% EMPTY  pkg 0402LF  page 307 : A = FM_UV_ADR_TRIGGER_N_R2 ; B = FM_UV_ADR_TRIGGER_N
R4660  Q_RES  0 5% CHIP  pkg 0402LF  page 167 : A = P2E_MB_BMC_TX_C_DN<0> ; B = P2E_MB_BMC_TX_C_R1_DN<0>

(kicad_pcb
	(version 20260206)
	(generator "pcbnew")
	(generator_version "10.0")
	(general
		(thickness 1.6)
		(legacy_teardrops no)
	)
	(paper "A4")
	(title_block
		(title "03242023_DA0F0TMBIJ0_F0T_Motherboard_J_brd_V01_OCP.brd")
		(comment 1 "Grand Teton / footprints 3958-3959 of 6105")
	)
	(layers
		(0 "F.Cu" signal "TOP")
		(4 "In1.Cu" signal "GND")
		(6 "In2.Cu" signal "IN1")
		(8 "In3.Cu" signal "GND1")
		(10 "In4.Cu" signal "IN2")
		(12 "In5.Cu" signal "GND2")
		(14 "In6.Cu" signal "IN3")
		(16 "In7.Cu" signal "GND3")
		(18 "In8.Cu" signal "VCC")
		(20 "In9.Cu" signal "VCC1")
		(22 "In10.Cu" signal "GND4")
		(24 "In11.Cu" signal "IN4")
		(26 "In12.Cu" signal "GND5")
		(28 "In13.Cu" signal "IN5")
		(30 "In14.Cu" signal "GND6")
		(32 "In15.Cu" signal "IN6")
		(34 "In16.Cu" signal "GND7")
		(2 "B.Cu" signal "BOTTOM")
		(9 "F.Adhes" user "F.Adhesive")
		(11 "B.Adhes" user "B.Adhesive")
		(13 "F.Paste" user "Package Geometry/Pastemask Top")
		(15 "B.Paste" user "Package Geometry/Pastemask Bottom")
		(5 "F.SilkS" user "Ref Des/Silkscreen Top")
		(7 "B.SilkS" user "Ref Des/Silkscreen Bottom")
		(1 "F.Mask" user "Board Geometry/Soldermask Top")
		(3 "B.Mask" user "Board Geometry/Soldermask Bottom")
		(17 "Dwgs.User" user "User.Drawings")
		(19 "Cmts.User" user "User.Comments")
		(21 "Eco1.User" user "User.Eco1")
		(23 "Eco2.User" user "User.Eco2")
		(25 "Edge.Cuts" user "Board Geometry/Outline")
		(27 "Margin" user)
		(31 "F.CrtYd" user "Package Geometry/Place Bound Top")
		(29 "B.CrtYd" user "Package Geometry/Place Bound Bottom")
		(35 "F.Fab" user "Ref Des/Assembly Top")
		(33 "B.Fab" user "Ref Des/Assembly Bottom")
	)
	(footprint ""
		(layer "F.Cu")
		(at 20.485608 -385.866894 90)
		(property "Reference" "R4660"
			(at 0 0 90)
			(layer "F.SilkS")
			(hide yes)
			(effects
				(font
					(size 1.27 1.27)
				)
			)
		)
		(property "Value" ""
			(at 0 0 90)
			(layer "F.Fab")
			(effects
				(font
					(size 1.27 1.27)
				)
			)
		)
		(duplicate_pad_numbers_are_jumpers no)
		(fp_line
			(start -0.015494 -0.4064)
			(end 0.7874 -0.4064)
			(stroke
				(width 0.1524)
				(type default)
			)
			(layer "F.SilkS")
		)
		(fp_line
			(start 0.7874 0.4064)
			(end -0.7874 0.4064)
			(stroke
				(width 0.1524)
				(type default)
			)
			(layer "F.SilkS")
		)
		(fp_line
			(start -0.7874 0.4064)
			(end -0.7874 -0.4064)
			(stroke
				(width 0.1524)
				(type default)
			)
			(layer "F.SilkS")
		)
		(fp_line
			(start -0.12065 -0.305054)
			(end -0.12065 -0.2794)
			(stroke
				(width 0.1)
				(type default)
			)
			(layer "F.Fab")
		)
		(fp_line
			(start -0.67945 -0.305054)
			(end -0.12065 -0.305054)
			(stroke
				(width 0.1)
				(type default)
			)
			(layer "F.Fab")
		)
		(fp_line
			(start 0.67945 -0.3048)
			(end 0.67945 0.3048)
			(stroke
				(width 0.1)
				(type default)
			)
			(layer "F.Fab")
		)
		(fp_line
			(start 0.12065 -0.3048)
			(end 0.67945 -0.3048)
			(stroke
				(width 0.1)
				(type default)
			)
			(layer "F.Fab")
		)
		(fp_line
			(start 0.12065 -0.2794)
			(end 0.12065 -0.3048)
			(stroke
				(width 0.1)
				(type default)
			)
			(layer "F.Fab")
		)
		(fp_line
			(start -0.12065 -0.2794)
			(end 0.12065 -0.2794)
			(stroke
				(width 0.1)
				(type default)
			)
			(layer "F.Fab")
		)
		(fp_line
			(start 0.120396 0.2794)
			(end -0.12065 0.2794)
			(stroke
				(width 0.1)
				(type default)
			)
			(layer "F.Fab")
		)
		(fp_line
			(start -0.12065 0.2794)
			(end -0.12065 0.3048)
			(stroke
				(width 0.1)
				(type default)
			)
			(layer "F.Fab")
		)
		(fp_line
			(start 0.67945 0.3048)
			(end 0.120396 0.3048)
			(stroke
				(width 0.1)
				(type default)
			)
			(layer "F.Fab")
		)
		(fp_line
			(start 0.120396 0.3048)
			(end 0.120396 0.2794)
			(stroke
				(width 0.1)
				(type default)
			)
			(layer "F.Fab")
		)
		(fp_line
			(start -0.12065 0.3048)
			(end -0.67945 0.3048)
			(stroke
				(width 0.1)
				(type default)
			)
			(layer "F.Fab")
		)
		(fp_line
			(start -0.67945 0.3048)
			(end -0.67945 -0.305054)
			(stroke
				(width 0.1)
				(type default)
			)
			(layer "F.Fab")
		)
		(pad "1" smd rect
			(at -0.40005 0 270)
			(size 0.4572 0.508)
			(layers "F.Cu" "F.Mask" "F.Paste")
			(net "P2E_MB_BMC_TX_C_DN<0>")
		)
		(pad "2" smd rect
			(at 0.40005 0 270)
			(size 0.4572 0.508)
			(layers "F.Cu" "F.Mask" "F.Paste")
			(net "P2E_MB_BMC_TX_C_R1_DN<0>")
		)
	)
	(footprint ""
		(layer "F.Cu")
		(at 206.7052 -97.6884 90)
		(property "Reference" "R4782"
			(at 0 0 90)
			(layer "F.SilkS")
			(hide yes)
			(effects
				(font
					(size 1.27 1.27)
				)
			)
		)
		(property "Value" ""
			(at 0 0 90)
			(layer "F.Fab")
			(effects
				(font
					(size 1.27 1.27)
				)
			)
		)
		(duplicate_pad_numbers_are_jumpers no)
		(fp_line
			(start 0.7874 -0.4064)
			(end 0.7874 0.4064)
			(stroke
				(width 0.1524)
				(type default)
			)
			(layer "F.SilkS")
		)
		(fp_line
			(start -0.7874 -0.4064)
			(end 0.7874 -0.4064)
			(stroke
				(width 0.1524)
				(type default)
			)
			(layer "F.SilkS")
		)
		(fp_line
			(start 0.7874 0.4064)
			(end -0.7874 0.4064)
			(stroke
				(width 0.1524)
				(type default)
			)
			(layer "F.SilkS")
		)
		(fp_line
			(start -0.7874 0.4064)
			(end -0.7874 -0.4064)
			(stroke
				(width 0.1524)
				(type default)
			)
			(layer "F.SilkS")
		)
		(fp_line
			(start -0.12065 -0.305054)
			(end -0.12065 -0.2794)
			(stroke
				(width 0.1)
				(type default)
			)
			(layer "F.Fab")
		)
		(fp_line
			(start -0.67945 -0.305054)
			(end -0.12065 -0.305054)
			(stroke
				(width 0.1)
				(type default)
			)
			(layer "F.Fab")
		)
		(fp_line
			(start 0.67945 -0.3048)
			(end 0.67945 0.3048)
			(stroke
				(width 0.1)
				(type default)
			)
			(layer "F.Fab")
		)
		(fp_line
			(start 0.12065 -0.3048)
			(end 0.67945 -0.3048)
			(stroke
				(width 0.1)
				(type default)
			)
			(layer "F.Fab")
		)
		(fp_line
			(start 0.12065 -0.2794)
			(end 0.12065 -0.3048)
			(stroke
				(width 0.1)
				(type default)
			)
			(layer "F.Fab")
		)
		(fp_line
			(start -0.12065 -0.2794)
			(end 0.12065 -0.2794)
			(stroke
				(width 0.1)
				(type default)
			)
			(layer "F.Fab")
		)
		(fp_line
			(start 0.120396 0.2794)
			(end -0.12065 0.2794)
			(stroke
				(width 0.1)
				(type default)
			)
			(layer "F.Fab")
		)
		(fp_line
			(start -0.12065 0.2794)
			(end -0.12065 0.3048)
			(stroke
				(width 0.1)
				(type default)
			)
			(layer "F.Fab")
		)
		(fp_line
			(start 0.67945 0.3048)
			(end 0.120396 0.3048)
			(stroke
				(width 0.1)
				(type default)
			)
			(layer "F.Fab")
		)
		(fp_line
			(start 0.120396 0.3048)
			(end 0.120396 0.2794)
			(stroke
				(width 0.1)
				(type default)
			)
			(layer "F.Fab")
		)
		(fp_line
			(start -0.12065 0.3048)
			(end -0.67945 0.3048)
			(stroke
				(width 0.1)
				(type default)
			)
			(layer "F.Fab")
		)
		(fp_line
			(start -0.67945 0.3048)
			(end -0.67945 -0.305054)
			(stroke
				(width 0.1)
				(type default)
			)
			(layer "F.Fab")
		)
		(pad "1" smd circle
			(at -0.40005 0 90)
			(size 0 0)
			(layers "F.Cu" "F.Mask" "F.Paste")
			(net "FM_UV_ADR_TRIGGER_N_R2")
		)
		(pad "2" smd circle
			(at 0.40005 0 90)
			(size 0 0)
			(layers "F.Cu" "F.Mask" "F.Paste")
			(net "FM_UV_ADR_TRIGGER_N")
		)
	)
)
